#ISCELL
  mstr_symbols cad_note *
  *
#ISCELL
  mstr_symbols intel_corp_bpage *
  *
#ISCELL
  mstr_standard offpage *
  page146_i100
#ISCELL
  mstr_standard offpage *
  page146_i102
#ISCELL
  mstr_standard offpage *
  page146_i103
#CELL
  w_hdl ast2520a1-gp-gp *
  page146_i104
#CELL
  w_hdl ast2520a1-gp-gp *
  page146_i105
#ISCELL
  mstr_standard offpage *
  page146_i106
#ISCELL
  mstr_standard offpage *
  page146_i17
#ISCELL
  mstr_standard offpage *
  page146_i18
#ISCELL
  mstr_standard offpage *
  page146_i19
#ISCELL
  mstr_standard offpage *
  page146_i21
#ISCELL
  mstr_standard offpage *
  page146_i23
#ISCELL
  mstr_standard offpage *
  page146_i24
#ISCELL
  mstr_standard offpage *
  page146_i25
#CELL
  mstr_discrete res *
  page146_i26
#CELL
  mstr_discrete res *
  page146_i27
#ISCELL
  mstr_standard offpage *
  page146_i28
#ISCELL
  mstr_standard offpage *
  page146_i29
#ISCELL
  mstr_standard offpage *
  page146_i30
#ISCELL
  mstr_standard offpage *
  page146_i31
#ISCELL
  mstr_standard offpage *
  page146_i32
#ISCELL
  mstr_standard offpage *
  page146_i33
#CELL
  mstr_discrete res *
  page146_i35
#ISCELL
  mstr_symbols gnd *
  page146_i36
#CELL
  mstr_discrete res *
  page146_i37
#ISCELL
  mstr_standard offpage *
  page146_i38
#ISCELL
  mstr_standard offpage *
  page146_i39
#ISCELL
  mstr_standard offpage *
  page146_i4
#ISCELL
  mstr_standard offpage *
  page146_i40
#ISCELL
  mstr_standard offpage *
  page146_i41
#ISCELL
  mstr_standard offpage *
  page146_i42
#ISCELL
  mstr_standard offpage *
  page146_i43
#ISCELL
  mstr_standard offpage *
  page146_i44
#ISCELL
  mstr_standard offpage *
  page146_i45
#ISCELL
  mstr_standard offpage *
  page146_i46
#ISCELL
  mstr_standard offpage *
  page146_i47
#ISCELL
  mstr_standard offpage *
  page146_i48
#ISCELL
  mstr_standard offpage *
  page146_i49
#ISCELL
  mstr_standard offpage *
  page146_i5
#CELL
  mstr_discrete res *
  page146_i51
#ISCELL
  mstr_symbols p3v3_stby *
  page146_i52
#ISCELL
  mstr_standard offpage *
  page146_i54
#ISCELL
  mstr_standard offpage *
  page146_i55
#ISCELL
  mstr_standard offpage *
  page146_i56
#ISCELL
  mstr_standard offpage *
  page146_i57
#ISCELL
  mstr_standard offpage *
  page146_i59
#ISCELL
  mstr_standard offpage *
  page146_i60
#ISCELL
  mstr_standard offpage *
  page146_i61
#ISCELL
  mstr_standard offpage *
  page146_i62
#ISCELL
  mstr_standard offpage *
  page146_i63
#CELL
  mstr_discrete res *
  page146_i64
#CELL
  mstr_discrete res *
  page146_i65
#ISCELL
  mstr_symbols gnd *
  page146_i66
#CELL
  mstr_discrete res *
  page146_i67
#CELL
  mstr_discrete res *
  page146_i68
#CELL
  mstr_discrete res *
  page146_i69
#CELL
  mstr_discrete res *
  page146_i70
#CELL
  mstr_discrete res *
  page146_i71
#CELL
  mstr_discrete res *
  page146_i72
#CELL
  mstr_discrete res *
  page146_i73
#CELL
  mstr_discrete res *
  page146_i74
#CELL
  mstr_discrete res *
  page146_i75
#CELL
  mstr_discrete res *
  page146_i76
#ISCELL
  mstr_symbols gnd *
  page146_i77
#CELL
  mstr_discrete res *
  page146_i78
#ISCELL
  mstr_symbols gnd *
  page146_i79
#ISCELL
  mstr_standard offpage *
  page146_i80
#ISCELL
  mstr_standard offpage *
  page146_i81
#ISCELL
  mstr_standard offpage *
  page146_i82
#ISCELL
  mstr_standard offpage *
  page146_i83
#CELL
  mstr_discrete res *
  page146_i84
#CELL
  mstr_discrete res *
  page146_i85
#ISCELL
  mstr_standard offpage *
  page146_i86
#ISCELL
  mstr_standard offpage *
  page146_i87
#ISCELL
  mstr_standard offpage *
  page146_i88
#ISCELL
  mstr_standard offpage *
  page146_i89
#ISCELL
  mstr_standard tap *
  page146_i90
#ISCELL
  mstr_standard tap *
  page146_i91
#ISCELL
  mstr_standard tap *
  page146_i92
#ISCELL
  mstr_standard tap *
  page146_i93
#ISCELL
  mstr_standard offpage *
  page146_i94
#ISCELL
  mstr_standard offpage *
  page146_i95
#CELL
  mstr_discrete res *
  page146_i96
#ISCELL
  mstr_standard offpage *
  page146_i97
#ISCELL
  mstr_standard offpage *
  page146_i98
#ISCELL
  mstr_standard offpage *
  page146_i99
